(kicad_pcb
	(version 20260206)
	(generator "pcbnew")
	(generator_version "10.0")
	(general
		(thickness 1.6)
		(legacy_teardrops no)
	)
	(paper "A4")
	(title_block
		(title "04192023_DAF0TMB3IC0_F0TG_MB_C_brd_V02_OCP.brd")
		(comment 1 "Grand Teton / footprint 1669 of 8354 (U18), pads 427-484 of 484")
	)
	(layers
		(0 "F.Cu" signal "TOP")
		(4 "In1.Cu" signal "GND")
		(6 "In2.Cu" signal "IN1")
		(8 "In3.Cu" signal "GND1")
		(10 "In4.Cu" signal "IN2")
		(12 "In5.Cu" signal "GND2")
		(14 "In6.Cu" signal "IN3")
		(16 "In7.Cu" signal "GND3")
		(18 "In8.Cu" signal "VCC")
		(20 "In9.Cu" signal "VCC1")
		(22 "In10.Cu" signal "GND4")
		(24 "In11.Cu" signal "IN4")
		(26 "In12.Cu" signal "GND5")
		(28 "In13.Cu" signal "IN5")
		(30 "In14.Cu" signal "GND6")
		(32 "In15.Cu" signal "IN6")
		(34 "In16.Cu" signal "GND7")
		(2 "B.Cu" signal "BOTTOM")
		(9 "F.Adhes" user "F.Adhesive")
		(11 "B.Adhes" user "B.Adhesive")
		(13 "F.Paste" user "Package Geometry/Pastemask Top")
		(15 "B.Paste" user "Package Geometry/Pastemask Bottom")
		(5 "F.SilkS" user "Ref Des/Silkscreen Top")
		(7 "B.SilkS" user "Ref Des/Silkscreen Bottom")
		(1 "F.Mask" user "Board Geometry/Soldermask Top")
		(3 "B.Mask" user "Board Geometry/Soldermask Bottom")
		(17 "Dwgs.User" user "User.Drawings")
		(19 "Cmts.User" user "User.Comments")
		(21 "Eco1.User" user "User.Eco1")
		(23 "Eco2.User" user "User.Eco2")
		(25 "Edge.Cuts" user "Board Geometry/Outline")
		(27 "Margin" user)
		(31 "F.CrtYd" user "Package Geometry/Place Bound Top")
		(29 "B.CrtYd" user "Package Geometry/Place Bound Bottom")
		(35 "F.Fab" user "Ref Des/Assembly Top")
		(33 "B.Fab" user "Ref Des/Assembly Bottom")
	)
	(footprint ""
		(layer "F.Cu")
		(at 185.522108 -115.052856 90)
		(property "Reference" "U18"
			(at -10.68451 -12.951206 0)
			(unlocked yes)
			(layer "F.SilkS")
			(effects
				(font
					(size 0.7874 0.5842)
					(thickness 0.1524)
				)
				(justify left)
			)
		)
		(property "Value" ""
			(at 0 0 90)
			(layer "F.Fab")
			(effects
				(font
					(size 1.27 1.27)
				)
			)
		)
		(duplicate_pad_numbers_are_jumpers no)
		(pad "V9" smd circle
			(at -1.999996 5.199888 90)
			(size 0.4064 0.4064)
			(layers "F.Cu" "F.Mask" "F.Paste")
			(net "FM_PVDD33_S5_EN")
		)
		(pad "V10" smd circle
			(at -1.199896 5.199888 90)
			(size 0.4064 0.4064)
			(layers "F.Cu" "F.Mask" "F.Paste")
			(net "FM_LED_PWRGD_PVDDCR_CPU0_P1")
		)
		(pad "V11" smd circle
			(at -0.40005 5.199888 90)
			(size 0.4064 0.4064)
			(layers "F.Cu" "F.Mask" "F.Paste")
			(net "RST_PERST_CPU1_SWB_1_N")
		)
		(pad "V12" smd circle
			(at 0.40005 5.199888 90)
			(size 0.4064 0.4064)
			(layers "F.Cu" "F.Mask" "F.Paste")
			(net "P3V3_E1S_0_EN_R")
		)
		(pad "V13" smd circle
			(at 1.199896 5.199888 90)
			(size 0.4064 0.4064)
			(layers "F.Cu" "F.Mask" "F.Paste")
			(net "GPU_3V3IO_RSVD4_ISO_R")
		)
		(pad "V14" smd circle
			(at 1.999996 5.199888 90)
			(size 0.4064 0.4064)
			(layers "F.Cu" "F.Mask" "F.Paste")
			(net "PRSNT_CABLE_GPU_A2_ISO_R_N")
		)
		(pad "V15" smd circle
			(at 2.800096 5.199888 90)
			(size 0.4064 0.4064)
			(layers "F.Cu" "F.Mask" "F.Paste")
			(net "BIC_MONITER_ISO_R")
		)
		(pad "V16" smd circle
			(at 3.599942 5.199888 90)
			(size 0.4064 0.4064)
			(layers "F.Cu" "F.Mask" "F.Paste")
			(net "RST_PERST_M2_0_R_N")
		)
		(pad "V17" smd circle
			(at 4.400042 5.199888 90)
			(size 0.4064 0.4064)
			(layers "F.Cu" "F.Mask" "F.Paste")
			(net "P3V3_OCP_V3_2_EN_R")
		)
		(pad "V18" smd circle
			(at 5.199888 5.199888 90)
			(size 0.4064 0.4064)
			(layers "F.Cu" "F.Mask" "F.Paste")
			(net "RST_SMB_RT_ROM_R2_N")
		)
		(pad "V19" smd circle
			(at 5.999988 5.199888 90)
			(size 0.4064 0.4064)
			(layers "F.Cu" "F.Mask" "F.Paste")
			(net "TP_FM_CLK_BUFFER_EN_R")
		)
		(pad "V20" smd circle
			(at 6.800088 5.199888 90)
			(size 0.4064 0.4064)
			(layers "F.Cu" "F.Mask" "F.Paste")
			(net "P1V8_AUX")
		)
		(pad "V21" smd circle
			(at 7.599934 5.199888 90)
			(size 0.4064 0.4064)
			(layers "F.Cu" "F.Mask" "F.Paste")
			(net "GND")
		)
		(pad "V22" smd circle
			(at 8.400034 5.199888 90)
			(size 0.4064 0.4064)
			(layers "F.Cu" "F.Mask" "F.Paste")
			(net "FM_BIOS_USB_RECOVERY")
		)
		(pad "W1" smd circle
			(at -8.400034 5.999988 90)
			(size 0.4064 0.4064)
			(layers "F.Cu" "F.Mask" "F.Paste")
			(net "PWRGD_CHAF_CPU0_R2")
		)
		(pad "W2" smd circle
			(at -7.599934 5.999988 90)
			(size 0.4064 0.4064)
			(layers "F.Cu" "F.Mask" "F.Paste")
			(net "P12V_OCP_V3_1_PWRGD")
		)
		(pad "W3" smd circle
			(at -6.800088 5.999988 90)
			(size 0.4064 0.4064)
			(layers "F.Cu" "F.Mask" "F.Paste")
			(net "PVDDCR_SOC_P0_EN")
		)
		(pad "W4" smd circle
			(at -5.999988 5.999988 90)
			(size 0.4064 0.4064)
			(layers "F.Cu" "F.Mask" "F.Paste")
			(net "FM_PVDD11_S3_P0_EN")
		)
		(pad "W5" smd circle
			(at -5.199888 5.999988 90)
			(size 0.4064 0.4064)
			(layers "F.Cu" "F.Mask" "F.Paste")
			(net "FM_PVDDCR_CPU0_P1_R_EN")
		)
		(pad "W6" smd circle
			(at -4.400042 5.999988 90)
			(size 0.4064 0.4064)
			(layers "F.Cu" "F.Mask" "F.Paste")
			(net "FM_GPU_PWR_EN")
		)
		(pad "W7" smd circle
			(at -3.599942 5.999988 90)
			(size 0.4064 0.4064)
			(layers "F.Cu" "F.Mask" "F.Paste")
			(net "P3V3_AUX")
		)
		(pad "W8" smd circle
			(at -2.800096 5.999988 90)
			(size 0.4064 0.4064)
			(layers "F.Cu" "F.Mask" "F.Paste")
			(net "PWRGD_P3V3_AUX_R")
		)
		(pad "W9" smd circle
			(at -1.999996 5.999988 90)
			(size 0.4064 0.4064)
			(layers "F.Cu" "F.Mask" "F.Paste")
			(net "FM_CPU0_PWR_GOOD")
		)
		(pad "W10" smd circle
			(at -1.199896 5.999988 90)
			(size 0.4064 0.4064)
			(layers "F.Cu" "F.Mask" "F.Paste")
			(net "FM_PLD_OCP_SFF_PWR_GOOD_R")
		)
		(pad "W11" smd circle
			(at -0.40005 5.999988 90)
			(size 0.4064 0.4064)
			(layers "F.Cu" "F.Mask" "F.Paste")
			(net "P3V3_AUX")
		)
		(pad "W12" smd circle
			(at 0.40005 5.999988 90)
			(size 0.4064 0.4064)
			(layers "F.Cu" "F.Mask" "F.Paste")
			(net "GND")
		)
		(pad "W13" smd circle
			(at 1.199896 5.999988 90)
			(size 0.4064 0.4064)
			(layers "F.Cu" "F.Mask" "F.Paste")
			(net "GPU_3V3IO_RSVD0_FFU_ISO_R")
		)
		(pad "W14" smd circle
			(at 1.999996 5.999988 90)
			(size 0.4064 0.4064)
			(layers "F.Cu" "F.Mask" "F.Paste")
			(net "GPU_FPGA_THERM_OVERT_ISO_R_N")
		)
		(pad "W15" smd circle
			(at 2.800096 5.999988 90)
			(size 0.4064 0.4064)
			(layers "F.Cu" "F.Mask" "F.Paste")
			(net "GPU_WP_HW_CTRL_R_N")
		)
		(pad "W16" smd circle
			(at 3.599942 5.999988 90)
			(size 0.4064 0.4064)
			(layers "F.Cu" "F.Mask" "F.Paste")
			(net "P3V3_AUX")
		)
		(pad "W17" smd circle
			(at 4.400042 5.999988 90)
			(size 0.4064 0.4064)
			(layers "F.Cu" "F.Mask" "F.Paste")
			(net "RST_PERST_OCP_SFF_N")
		)
		(pad "W18" smd circle
			(at 5.199888 5.999988 90)
			(size 0.4064 0.4064)
			(layers "F.Cu" "F.Mask" "F.Paste")
			(net "FM_AC_PWR_BTN_PLD_ISO_N")
		)
		(pad "W19" smd circle
			(at 5.999988 5.999988 90)
			(size 0.4064 0.4064)
			(layers "F.Cu" "F.Mask" "F.Paste")
			(net "FM_CPU1_FORCE_SELFREFRESH")
		)
		(pad "W20" smd circle
			(at 6.800088 5.999988 90)
			(size 0.4064 0.4064)
			(layers "F.Cu" "F.Mask" "F.Paste")
			(net "FM_FORCE_ALL_PWRON_R")
		)
		(pad "W21" smd circle
			(at 7.599934 5.999988 90)
			(size 0.4064 0.4064)
			(layers "F.Cu" "F.Mask" "F.Paste")
			(net "FM_ROM_SD_LS_OE")
		)
		(pad "W22" smd circle
			(at 8.400034 5.999988 90)
			(size 0.4064 0.4064)
			(layers "F.Cu" "F.Mask" "F.Paste")
			(net "FM_CPU1_NMI_SYNC_FLOOD_N")
		)
		(pad "Y1" smd circle
			(at -8.400034 6.800088 90)
			(size 0.4064 0.4064)
			(layers "F.Cu" "F.Mask" "F.Paste")
			(net "PWRGD_CHGL_CPU0_R2")
		)
		(pad "Y2" smd circle
			(at -7.599934 6.800088 90)
			(size 0.4064 0.4064)
			(layers "F.Cu" "F.Mask" "F.Paste")
			(net "PWRGD_PVDDCR_SOC_P0")
		)
		(pad "Y3" smd circle
			(at -6.800088 6.800088 90)
			(size 0.4064 0.4064)
			(layers "F.Cu" "F.Mask" "F.Paste")
			(net "PWRGD_PVDDCR_CPU0_P0")
		)
		(pad "Y4" smd circle
			(at -5.999988 6.800088 90)
			(size 0.4064 0.4064)
			(layers "F.Cu" "F.Mask" "F.Paste")
			(net "FM_PWRGD_PVDD11_S3_P0")
		)
		(pad "Y5" smd circle
			(at -5.199888 6.800088 90)
			(size 0.4064 0.4064)
			(layers "F.Cu" "F.Mask" "F.Paste")
			(net "FM_PWRGD_PVDDCR_CPU0_P1")
		)
		(pad "Y6" smd circle
			(at -4.400042 6.800088 90)
			(size 0.4064 0.4064)
			(layers "F.Cu" "F.Mask" "F.Paste")
			(net "P12V_SCM_PWRGD_R")
		)
		(pad "Y7" smd circle
			(at -3.599942 6.800088 90)
			(size 0.4064 0.4064)
			(layers "F.Cu" "F.Mask" "F.Paste")
			(net "GND")
		)
		(pad "Y8" smd circle
			(at -2.800096 6.800088 90)
			(size 0.4064 0.4064)
			(layers "F.Cu" "F.Mask" "F.Paste")
			(net "PWRGD_P1V8_AUX_R")
		)
		(pad "Y9" smd circle
			(at -1.999996 6.800088 90)
			(size 0.4064 0.4064)
			(layers "F.Cu" "F.Mask" "F.Paste")
			(net "PWRGD_P1V2_AUX_R")
		)
		(pad "Y10" smd circle
			(at -1.199896 6.800088 90)
			(size 0.4064 0.4064)
			(layers "F.Cu" "F.Mask" "F.Paste")
			(net "BMC_FPGA_LED2")
		)
		(pad "Y11" smd circle
			(at -0.40005 6.800088 90)
			(size 0.4064 0.4064)
			(layers "F.Cu" "F.Mask" "F.Paste")
			(net "FM_LED_PWRGD_PVDDIO_P0")
		)
		(pad "Y12" smd circle
			(at 0.40005 6.800088 90)
			(size 0.4064 0.4064)
			(layers "F.Cu" "F.Mask" "F.Paste")
			(net "FM_LED_PWRGD_PVDD11_S3_P0")
		)
		(pad "Y13" smd circle
			(at 1.199896 6.800088 90)
			(size 0.4064 0.4064)
			(layers "F.Cu" "F.Mask" "F.Paste")
			(net "SWB_HSC_EN_R")
		)
		(pad "Y14" smd circle
			(at 1.999996 6.800088 90)
			(size 0.4064 0.4064)
			(layers "F.Cu" "F.Mask" "F.Paste")
			(net "SWB_HSC_PWRGD_ISO_R")
		)
		(pad "Y15" smd circle
			(at 2.800096 6.800088 90)
			(size 0.4064 0.4064)
			(layers "F.Cu" "F.Mask" "F.Paste")
			(net "GPU_FPGA_OVERT_ISO_R_N")
		)
		(pad "Y16" smd circle
			(at 3.599942 6.800088 90)
			(size 0.4064 0.4064)
			(layers "F.Cu" "F.Mask" "F.Paste")
			(net "GND")
		)
		(pad "Y17" smd circle
			(at 4.400042 6.800088 90)
			(size 0.4064 0.4064)
			(layers "F.Cu" "F.Mask" "F.Paste")
			(net "SW_P3V3_EN")
		)
		(pad "Y18" smd circle
			(at 5.199888 6.800088 90)
			(size 0.4064 0.4064)
			(layers "F.Cu" "F.Mask" "F.Paste")
			(net "FM_SMB_2_ALERT_GPU_ISO_R_N")
		)
		(pad "Y19" smd circle
			(at 5.999988 6.800088 90)
			(size 0.4064 0.4064)
			(layers "F.Cu" "F.Mask" "F.Paste")
			(net "GPU_BASE_STBY_EN_R")
		)
		(pad "Y20" smd circle
			(at 6.800088 6.800088 90)
			(size 0.4064 0.4064)
			(layers "F.Cu" "F.Mask" "F.Paste")
			(net "RST_SMB_RT_R2_N")
		)
		(pad "Y21" smd circle
			(at 7.599934 6.800088 90)
			(size 0.4064 0.4064)
			(layers "F.Cu" "F.Mask" "F.Paste")
			(net "FM_CPU1_PWR_GD_IN")
		)
		(pad "Y22" smd circle
			(at 8.400034 6.800088 90)
			(size 0.4064 0.4064)
			(layers "F.Cu" "F.Mask" "F.Paste")
			(net "FM_ROM_LS_EN")
		)
	)
)
